# TIMECARD (Time Appliance Project (Time Card)) — schematic netlist excerpt (pin names and nets, part order shuffled) for the footprints in the layout excerpt that follows; sources: Cadence DE-HDL packaged netlist, KiCad conversion of R4006-B0001-02_R01.brd

R190  RESISTOR  3.24KOHM 1%  pkg SMC_0402R_H014  page 30 : \1\ = SG ; \2\ = XP1R8V_FB
R274  RESISTOR  100OHM 1%  pkg SMC_0402R_H016  page 26 : \1\ = FPGA_OUT_SMA2_LED_GREEN_N ; \2\ = UNNAMED_14_LED4PV14_I266_4

(kicad_pcb
	(version 20260206)
	(generator "pcbnew")
	(generator_version "10.0")
	(general
		(thickness 1.6)
		(legacy_teardrops no)
	)
	(paper "A4")
	(title_block
		(title "timecard-production-celestica-r4006 — R4006-B0001-02_R01.brd")
		(comment 1 "Time Appliance Project (Time Card) / footprints 222-223 of 1113")
	)
	(layers
		(0 "F.Cu" signal "TOP")
		(4 "In1.Cu" signal "L02_GND1")
		(6 "In2.Cu" signal "L03_SIG1")
		(8 "In3.Cu" signal "L04_GND2")
		(10 "In4.Cu" signal "L05_VCC1")
		(12 "In5.Cu" signal "L06_VCC2")
		(14 "In6.Cu" signal "L07_GND3")
		(16 "In7.Cu" signal "L08_SIG2")
		(18 "In8.Cu" signal "L09_GND4")
		(2 "B.Cu" signal "BOTTOM")
		(9 "F.Adhes" user "F.Adhesive")
		(11 "B.Adhes" user "B.Adhesive")
		(13 "F.Paste" user "Package Geometry/Pastemask Top")
		(15 "B.Paste" user "Package Geometry/Pastemask Bottom")
		(5 "F.SilkS" user "Ref Des/Silkscreen Top")
		(7 "B.SilkS" user "Ref Des/Silkscreen Bottom")
		(1 "F.Mask" user "Board Geometry/Soldermask Top")
		(3 "B.Mask" user "Board Geometry/Soldermask Bottom")
		(17 "Dwgs.User" user "User.Drawings")
		(19 "Cmts.User" user "User.Comments")
		(21 "Eco1.User" user "User.Eco1")
		(23 "Eco2.User" user "User.Eco2")
		(25 "Edge.Cuts" user "Board Geometry/Outline")
		(27 "Margin" user)
		(31 "F.CrtYd" user "Package Geometry/Place Bound Top")
		(29 "B.CrtYd" user "Package Geometry/Place Bound Bottom")
		(35 "F.Fab" user "Ref Des/Assembly Top")
		(33 "B.Fab" user "Ref Des/Assembly Bottom")
	)
	(footprint ""
		(layer "F.Cu")
		(at 135.3312 -66.8528 90)
		(property "Reference" "R190"
			(at -4.8768 0.34417 90)
			(unlocked yes)
			(layer "F.SilkS")
			(effects
				(font
					(size 0.7874 0.5842)
					(thickness 0.1524)
				)
			)
		)
		(property "Value" "VAL*"
			(at 0.02032 2.13233 90)
			(unlocked yes)
			(layer "F.Fab")
			(hide yes)
			(effects
				(font
					(size 0.7874 0.5842)
					(thickness 0.1524)
				)
			)
		)
		(property "Tolerance" "TOL*"
			(at 0.044704 3.05435 90)
			(unlocked yes)
			(layer "Cmts.User")
			(hide yes)
			(effects
				(font
					(size 0.7874 0.5842)
					(thickness 0.1524)
				)
			)
		)
		(property "User Part Number" "PARTNUM*"
			(at 0.02032 4.024884 90)
			(unlocked yes)
			(layer "Cmts.User")
			(hide yes)
			(effects
				(font
					(size 0.7874 0.5842)
					(thickness 0.1524)
				)
			)
		)
		(property "Device Type" "RESISTOR-G155-03241-01,3.24KOHA"
			(at 0.008382 1.210564 90)
			(unlocked yes)
			(layer "F.Fab")
			(hide yes)
			(effects
				(font
					(size 0.7874 0.5842)
					(thickness 0.1524)
				)
			)
		)
		(duplicate_pad_numbers_are_jumpers no)
		(fp_line
			(start 1.143 -0.5588)
			(end -1.143 -0.5588)
			(stroke
				(width 0.1)
				(type default)
			)
			(layer "F.SilkS")
		)
		(fp_line
			(start -1.143 -0.5588)
			(end -1.143 0.5588)
			(stroke
				(width 0.1)
				(type default)
			)
			(layer "F.SilkS")
		)
		(fp_line
			(start 1.143 0.5588)
			(end 1.143 -0.5588)
			(stroke
				(width 0.1)
				(type default)
			)
			(layer "F.SilkS")
		)
		(fp_line
			(start -1.143 0.5588)
			(end 1.143 0.5588)
			(stroke
				(width 0.1)
				(type default)
			)
			(layer "F.SilkS")
		)
		(fp_rect
			(start 1.143 0.5588)
			(end -1.143 -0.5588)
			(stroke
				(width 0)
				(type default)
			)
			(fill no)
			(layer "F.CrtYd")
		)
		(fp_line
			(start 0.508 -0.3048)
			(end -0.508 -0.3048)
			(stroke
				(width 0.1)
				(type default)
			)
			(layer "F.Fab")
		)
		(fp_line
			(start -0.508 -0.3048)
			(end -0.508 0.3048)
			(stroke
				(width 0.1)
				(type default)
			)
			(layer "F.Fab")
		)
		(fp_line
			(start 0.508 0.3048)
			(end 0.508 -0.3048)
			(stroke
				(width 0.1)
				(type default)
			)
			(layer "F.Fab")
		)
		(fp_line
			(start -0.508 0.3048)
			(end 0.508 0.3048)
			(stroke
				(width 0.1)
				(type default)
			)
			(layer "F.Fab")
		)
		(pad "1" smd rect
			(at -0.5334 0 90)
			(size 0.7112 0.6096)
			(layers "F.Cu" "F.Mask" "F.Paste")
			(net "SG")
		)
		(pad "2" smd rect
			(at 0.5334 0 90)
			(size 0.7112 0.6096)
			(layers "F.Cu" "F.Mask" "F.Paste")
			(net "XP1R8V_FB")
		)
		(zone
			(layer "F.Cu")
			(hatch none 0.5)
			(connect_pads
				(clearance 0)
			)
			(min_thickness 0.25)
			(keepout
				(tracks allowed)
				(vias not_allowed)
				(pads allowed)
				(copperpour not_allowed)
				(footprints allowed)
			)
			(placement
				(enabled no)
				(sheetname "")
			)
			(fill
				(thermal_gap 0.5)
				(thermal_bridge_width 0.5)
				(island_removal_mode 0)
			)
			(polygon
				(pts
					(xy 135.636 -66.929) (xy 135.0264 -66.929) (xy 135.0264 -66.7766) (xy 135.636 -66.7766)
				)
			)
		)
	)
	(footprint ""
		(layer "F.Cu")
		(at 20.32 -31.75 180)
		(property "Reference" "R274"
			(at -2.794 -0.67437 0)
			(unlocked yes)
			(layer "F.SilkS")
			(effects
				(font
					(size 0.7874 0.5842)
					(thickness 0.1524)
				)
			)
		)
		(property "Value" "VAL*"
			(at 0.02032 2.13233 180)
			(unlocked yes)
			(layer "F.Fab")
			(hide yes)
			(effects
				(font
					(size 0.7874 0.5842)
					(thickness 0.1524)
				)
			)
		)
		(property "Device Type" "RESISTOR-G155-11000-01,100OHM,A"
			(at 0.008382 1.210564 180)
			(unlocked yes)
			(layer "F.Fab")
			(hide yes)
			(effects
				(font
					(size 0.7874 0.5842)
					(thickness 0.1524)
				)
			)
		)
		(property "User Part Number" "PARTNUM*"
			(at 0.02032 4.024884 180)
			(unlocked yes)
			(layer "Cmts.User")
			(hide yes)
			(effects
				(font
					(size 0.7874 0.5842)
					(thickness 0.1524)
				)
			)
		)
		(property "Tolerance" "TOL*"
			(at 0.044704 3.05435 180)
			(unlocked yes)
			(layer "Cmts.User")
			(hide yes)
			(effects
				(font
					(size 0.7874 0.5842)
					(thickness 0.1524)
				)
			)
		)
		(duplicate_pad_numbers_are_jumpers no)
		(fp_line
			(start 1.143 0.5588)
			(end 1.143 -0.5588)
			(stroke
				(width 0.1)
				(type default)
			)
			(layer "F.SilkS")
		)
		(fp_line
			(start 1.143 -0.5588)
			(end -1.143 -0.5588)
			(stroke
				(width 0.1)
				(type default)
			)
			(layer "F.SilkS")
		)
		(fp_line
			(start -1.143 0.5588)
			(end 1.143 0.5588)
			(stroke
				(width 0.1)
				(type default)
			)
			(layer "F.SilkS")
		)
		(fp_line
			(start -1.143 -0.5588)
			(end -1.143 0.5588)
			(stroke
				(width 0.1)
				(type default)
			)
			(layer "F.SilkS")
		)
		(fp_poly
			(pts
				(xy -1.143 0.5588) (xy 1.143 0.5588) (xy 1.143 -0.5588) (xy -1.143 -0.5588)
			)
			(stroke
				(width 0)
				(type default)
			)
			(fill no)
			(layer "F.CrtYd")
		)
		(fp_line
			(start 0.508 0.3048)
			(end 0.508 -0.3048)
			(stroke
				(width 0.1)
				(type default)
			)
			(layer "F.Fab")
		)
		(fp_line
			(start 0.508 -0.3048)
			(end -0.508 -0.3048)
			(stroke
				(width 0.1)
				(type default)
			)
			(layer "F.Fab")
		)
		(fp_line
			(start -0.508 0.3048)
			(end 0.508 0.3048)
			(stroke
				(width 0.1)
				(type default)
			)
			(layer "F.Fab")
		)
		(fp_line
			(start -0.508 -0.3048)
			(end -0.508 0.3048)
			(stroke
				(width 0.1)
				(type default)
			)
			(layer "F.Fab")
		)
		(pad "1" smd rect
			(at -0.5334 0 180)
			(size 0.7112 0.6096)
			(layers "F.Cu" "F.Mask" "F.Paste")
			(net "FPGA_OUT_SMA2_LED_GREEN_N")
		)
		(pad "2" smd rect
			(at 0.5334 0 180)
			(size 0.7112 0.6096)
			(layers "F.Cu" "F.Mask" "F.Paste")
			(net "UNNAMED_14_LED4PV14_I266_4")
		)
		(zone
			(layer "F.Cu")
			(hatch none 0.5)
			(connect_pads
				(clearance 0)
			)
			(min_thickness 0.25)
			(keepout
				(tracks not_allowed)
				(vias allowed)
				(pads allowed)
				(copperpour not_allowed)
				(footprints allowed)
			)
			(placement
				(enabled no)
				(sheetname "")
			)
			(fill
				(thermal_gap 0.5)
				(thermal_bridge_width 0.5)
				(island_removal_mode 0)
			)
			(polygon
				(pts
					(xy 20.3962 -32.0548) (xy 20.2438 -32.0548) (xy 20.2438 -31.4452) (xy 20.3962 -31.4452)
				)
			)
		)
		(zone
			(layer "F.Cu")
			(hatch none 0.5)
			(connect_pads
				(clearance 0)
			)
			(min_thickness 0.25)
			(keepout
				(tracks allowed)
				(vias not_allowed)
				(pads allowed)
				(copperpour not_allowed)
				(footprints allowed)
			)
			(placement
				(enabled no)
				(sheetname "")
			)
			(fill
				(thermal_gap 0.5)
				(thermal_bridge_width 0.5)
				(island_removal_mode 0)
			)
			(polygon
				(pts
					(xy 20.3962 -32.0548) (xy 20.2438 -32.0548) (xy 20.2438 -31.4452) (xy 20.3962 -31.4452)
				)
			)
		)
	)
)
